(kicad_pcb
	(version 20260206)
	(generator "pcbnew")
	(generator_version "10.0")
	(general
		(thickness 1.6)
		(legacy_teardrops no)
	)
	(paper "A4")
	(title_block
		(title "9054_F0T_PDB_BD_GPU_F_V04_1213_1550_OCP.brd")
		(comment 1 "Grand Teton / footprints 87-92 of 608")
	)
	(layers
		(0 "F.Cu" signal "TOP")
		(4 "In1.Cu" signal "GND")
		(6 "In2.Cu" signal "IN1")
		(8 "In3.Cu" signal "GND1")
		(10 "In4.Cu" signal "VCC")
		(12 "In5.Cu" signal "VCC1")
		(14 "In6.Cu" signal "GND2")
		(16 "In7.Cu" signal "IN2")
		(18 "In8.Cu" signal "GND3")
		(2 "B.Cu" signal "BOTTOM")
		(9 "F.Adhes" user "F.Adhesive")
		(11 "B.Adhes" user "B.Adhesive")
		(13 "F.Paste" user "Package Geometry/Pastemask Top")
		(15 "B.Paste" user "Package Geometry/Pastemask Bottom")
		(5 "F.SilkS" user "Ref Des/Silkscreen Top")
		(7 "B.SilkS" user "Ref Des/Silkscreen Bottom")
		(1 "F.Mask" user "Board Geometry/Soldermask Top")
		(3 "B.Mask" user "Board Geometry/Soldermask Bottom")
		(17 "Dwgs.User" user "User.Drawings")
		(19 "Cmts.User" user "User.Comments")
		(21 "Eco1.User" user "User.Eco1")
		(23 "Eco2.User" user "User.Eco2")
		(25 "Edge.Cuts" user "Board Geometry/Outline")
		(27 "Margin" user)
		(31 "F.CrtYd" user "Package Geometry/Place Bound Top")
		(29 "B.CrtYd" user "Package Geometry/Place Bound Bottom")
		(35 "F.Fab" user "Ref Des/Assembly Top")
		(33 "B.Fab" user "Ref Des/Assembly Bottom")
	)
	(footprint ""
		(layer "F.Cu")
		(at 262.382 -51.181 180)
		(property "Reference" "U24"
			(at 4.0894 -1.04267 0)
			(unlocked yes)
			(layer "F.SilkS")
			(effects
				(font
					(size 0.7874 0.5842)
					(thickness 0.1524)
				)
				(justify left)
			)
		)
		(property "Value" ""
			(at 0 0 180)
			(layer "F.Fab")
			(effects
				(font
					(size 1.27 1.27)
				)
			)
		)
		(duplicate_pad_numbers_are_jumpers no)
		(fp_line
			(start 1.603248 1.500124)
			(end -1.603248 1.500124)
			(stroke
				(width 0.1524)
				(type default)
			)
			(layer "F.SilkS")
		)
		(fp_line
			(start 1.603248 -1.500124)
			(end 1.603248 1.500124)
			(stroke
				(width 0.1524)
				(type default)
			)
			(layer "F.SilkS")
		)
		(fp_line
			(start -1.603248 1.500124)
			(end -1.603248 -1.500124)
			(stroke
				(width 0.1524)
				(type default)
			)
			(layer "F.SilkS")
		)
		(fp_line
			(start -1.603248 -1.500124)
			(end 1.603248 -1.500124)
			(stroke
				(width 0.1524)
				(type default)
			)
			(layer "F.SilkS")
		)
		(fp_line
			(start 1.249934 0.219964)
			(end 1.249934 -0.219964)
			(stroke
				(width 0.1)
				(type default)
			)
			(layer "F.Fab")
		)
		(fp_line
			(start 1.249934 -0.219964)
			(end 0.700024 -0.219964)
			(stroke
				(width 0.1)
				(type default)
			)
			(layer "F.Fab")
		)
		(fp_line
			(start 0.700024 1.500124)
			(end 0.700024 0.219964)
			(stroke
				(width 0.1)
				(type default)
			)
			(layer "F.Fab")
		)
		(fp_line
			(start 0.700024 0.219964)
			(end 1.249934 0.219964)
			(stroke
				(width 0.1)
				(type default)
			)
			(layer "F.Fab")
		)
		(fp_line
			(start 0.700024 -0.219964)
			(end 0.700024 -1.500124)
			(stroke
				(width 0.1)
				(type default)
			)
			(layer "F.Fab")
		)
		(fp_line
			(start 0.700024 -1.500124)
			(end -0.700024 -1.500124)
			(stroke
				(width 0.1)
				(type default)
			)
			(layer "F.Fab")
		)
		(fp_line
			(start -0.6985 0.729996)
			(end -1.249934 0.729996)
			(stroke
				(width 0.1)
				(type default)
			)
			(layer "F.Fab")
		)
		(fp_line
			(start -0.6985 -0.729996)
			(end -0.6985 0.729996)
			(stroke
				(width 0.1)
				(type default)
			)
			(layer "F.Fab")
		)
		(fp_line
			(start -0.700024 1.500124)
			(end 0.700024 1.500124)
			(stroke
				(width 0.1)
				(type default)
			)
			(layer "F.Fab")
		)
		(fp_line
			(start -0.700024 1.169924)
			(end -0.700024 1.500124)
			(stroke
				(width 0.1)
				(type default)
			)
			(layer "F.Fab")
		)
		(fp_line
			(start -0.700024 -1.169924)
			(end -1.249934 -1.169924)
			(stroke
				(width 0.1)
				(type default)
			)
			(layer "F.Fab")
		)
		(fp_line
			(start -0.700024 -1.500124)
			(end -0.700024 -1.169924)
			(stroke
				(width 0.1)
				(type default)
			)
			(layer "F.Fab")
		)
		(fp_line
			(start -1.249934 1.169924)
			(end -0.700024 1.169924)
			(stroke
				(width 0.1)
				(type default)
			)
			(layer "F.Fab")
		)
		(fp_line
			(start -1.249934 0.729996)
			(end -1.249934 1.169924)
			(stroke
				(width 0.1)
				(type default)
			)
			(layer "F.Fab")
		)
		(fp_line
			(start -1.249934 -0.729996)
			(end -0.6985 -0.729996)
			(stroke
				(width 0.1)
				(type default)
			)
			(layer "F.Fab")
		)
		(fp_line
			(start -1.249934 -1.169924)
			(end -1.249934 -0.729996)
			(stroke
				(width 0.1)
				(type default)
			)
			(layer "F.Fab")
		)
		(fp_rect
			(start -0.700024 1.500124)
			(end 0.700024 -1.500124)
			(stroke
				(width 0)
				(type default)
			)
			(fill no)
			(layer "F.Fab")
		)
		(pad "D" smd rect
			(at 0.999998 0 90)
			(size 0.8128 0.9144)
			(layers "F.Cu" "F.Mask" "F.Paste")
			(net "GPU_HSC1_BUF_EN")
		)
		(pad "G" smd rect
			(at -0.999998 -0.94996 90)
			(size 0.8128 0.9144)
			(layers "F.Cu" "F.Mask" "F.Paste")
			(net "GPU_HSC1_BUF_EN_N")
		)
		(pad "S" smd rect
			(at -0.999998 0.94996 90)
			(size 0.8128 0.9144)
			(layers "F.Cu" "F.Mask" "F.Paste")
			(net "GND")
		)
	)
	(footprint ""
		(layer "F.Cu")
		(at 451.1802 -81.9658)
		(property "Reference" "PC52"
			(at 0 0 0)
			(layer "F.SilkS")
			(hide yes)
			(effects
				(font
					(size 1.27 1.27)
				)
			)
		)
		(property "Value" ""
			(at 0 0 0)
			(layer "F.Fab")
			(effects
				(font
					(size 1.27 1.27)
				)
			)
		)
		(duplicate_pad_numbers_are_jumpers no)
		(fp_line
			(start -0.7874 -0.4064)
			(end 0.7874 -0.4064)
			(stroke
				(width 0.1524)
				(type default)
			)
			(layer "F.SilkS")
		)
		(fp_line
			(start -0.7874 0.4064)
			(end -0.7874 -0.4064)
			(stroke
				(width 0.1524)
				(type default)
			)
			(layer "F.SilkS")
		)
		(fp_line
			(start 0.7874 -0.4064)
			(end 0.7874 0.4064)
			(stroke
				(width 0.1524)
				(type default)
			)
			(layer "F.SilkS")
		)
		(fp_line
			(start 0.7874 0.4064)
			(end -0.7874 0.4064)
			(stroke
				(width 0.1524)
				(type default)
			)
			(layer "F.SilkS")
		)
		(fp_line
			(start -0.67945 -0.305054)
			(end -0.12065 -0.305054)
			(stroke
				(width 0.1)
				(type default)
			)
			(layer "F.Fab")
		)
		(fp_line
			(start -0.67945 0.3048)
			(end -0.67945 -0.305054)
			(stroke
				(width 0.1)
				(type default)
			)
			(layer "F.Fab")
		)
		(fp_line
			(start -0.12065 -0.305054)
			(end -0.12065 -0.2794)
			(stroke
				(width 0.1)
				(type default)
			)
			(layer "F.Fab")
		)
		(fp_line
			(start -0.12065 -0.2794)
			(end 0.12065 -0.2794)
			(stroke
				(width 0.1)
				(type default)
			)
			(layer "F.Fab")
		)
		(fp_line
			(start -0.12065 0.2794)
			(end -0.12065 0.3048)
			(stroke
				(width 0.1)
				(type default)
			)
			(layer "F.Fab")
		)
		(fp_line
			(start -0.12065 0.3048)
			(end -0.67945 0.3048)
			(stroke
				(width 0.1)
				(type default)
			)
			(layer "F.Fab")
		)
		(fp_line
			(start 0.120396 0.2794)
			(end -0.12065 0.2794)
			(stroke
				(width 0.1)
				(type default)
			)
			(layer "F.Fab")
		)
		(fp_line
			(start 0.120396 0.3048)
			(end 0.120396 0.2794)
			(stroke
				(width 0.1)
				(type default)
			)
			(layer "F.Fab")
		)
		(fp_line
			(start 0.12065 -0.3048)
			(end 0.67945 -0.3048)
			(stroke
				(width 0.1)
				(type default)
			)
			(layer "F.Fab")
		)
		(fp_line
			(start 0.12065 -0.2794)
			(end 0.12065 -0.3048)
			(stroke
				(width 0.1)
				(type default)
			)
			(layer "F.Fab")
		)
		(fp_line
			(start 0.67945 -0.3048)
			(end 0.67945 0.3048)
			(stroke
				(width 0.1)
				(type default)
			)
			(layer "F.Fab")
		)
		(fp_line
			(start 0.67945 0.3048)
			(end 0.120396 0.3048)
			(stroke
				(width 0.1)
				(type default)
			)
			(layer "F.Fab")
		)
		(pad "1" smd circle
			(at -0.40005 0)
			(size 0 0)
			(layers "F.Cu" "F.Mask" "F.Paste")
			(net "SW_P3V3_HPDB_BT_R")
		)
		(pad "2" smd circle
			(at 0.40005 0)
			(size 0 0)
			(layers "F.Cu" "F.Mask" "F.Paste")
			(net "SW_P3V3_HPDB_PH")
		)
	)
	(footprint ""
		(layer "F.Cu")
		(at 306.7304 -68.199)
		(property "Reference" "PR6962"
			(at 0 0 0)
			(layer "F.SilkS")
			(hide yes)
			(effects
				(font
					(size 1.27 1.27)
				)
			)
		)
		(property "Value" ""
			(at 0 0 0)
			(layer "F.Fab")
			(effects
				(font
					(size 1.27 1.27)
				)
			)
		)
		(duplicate_pad_numbers_are_jumpers no)
		(fp_line
			(start -1.2954 -0.5842)
			(end 1.2954 -0.5842)
			(stroke
				(width 0.1524)
				(type default)
			)
			(layer "F.SilkS")
		)
		(fp_line
			(start -1.2954 0.5842)
			(end -1.2954 -0.5842)
			(stroke
				(width 0.1524)
				(type default)
			)
			(layer "F.SilkS")
		)
		(fp_line
			(start 1.2954 -0.5842)
			(end 1.2954 0.5842)
			(stroke
				(width 0.1524)
				(type default)
			)
			(layer "F.SilkS")
		)
		(fp_line
			(start 1.2954 0.5842)
			(end -1.2954 0.5842)
			(stroke
				(width 0.1524)
				(type default)
			)
			(layer "F.SilkS")
		)
		(fp_line
			(start -1.1938 -0.406654)
			(end -0.8636 -0.406654)
			(stroke
				(width 0.1)
				(type default)
			)
			(layer "F.Fab")
		)
		(fp_line
			(start -1.1938 0.4064)
			(end -1.1938 -0.406654)
			(stroke
				(width 0.1)
				(type default)
			)
			(layer "F.Fab")
		)
		(fp_line
			(start -0.8636 -0.4572)
			(end 0.8636 -0.4572)
			(stroke
				(width 0.1)
				(type default)
			)
			(layer "F.Fab")
		)
		(fp_line
			(start -0.8636 -0.406654)
			(end -0.8636 -0.4572)
			(stroke
				(width 0.1)
				(type default)
			)
			(layer "F.Fab")
		)
		(fp_line
			(start -0.8636 0.4064)
			(end -1.1938 0.4064)
			(stroke
				(width 0.1)
				(type default)
			)
			(layer "F.Fab")
		)
		(fp_line
			(start -0.8636 0.4318)
			(end -0.8636 0.4064)
			(stroke
				(width 0.1)
				(type default)
			)
			(layer "F.Fab")
		)
		(fp_line
			(start -0.8636 0.4572)
			(end -0.8636 0.4318)
			(stroke
				(width 0.1)
				(type default)
			)
			(layer "F.Fab")
		)
		(fp_line
			(start 0.8636 -0.4572)
			(end 0.8636 -0.406654)
			(stroke
				(width 0.1)
				(type default)
			)
			(layer "F.Fab")
		)
		(fp_line
			(start 0.8636 -0.406654)
			(end 1.1938 -0.406654)
			(stroke
				(width 0.1)
				(type default)
			)
			(layer "F.Fab")
		)
		(fp_line
			(start 0.8636 0.4064)
			(end 0.8636 0.4572)
			(stroke
				(width 0.1)
				(type default)
			)
			(layer "F.Fab")
		)
		(fp_line
			(start 0.8636 0.4572)
			(end -0.8636 0.4572)
			(stroke
				(width 0.1)
				(type default)
			)
			(layer "F.Fab")
		)
		(fp_line
			(start 1.1938 -0.406654)
			(end 1.1938 0.4064)
			(stroke
				(width 0.1)
				(type default)
			)
			(layer "F.Fab")
		)
		(fp_line
			(start 1.1938 0.4064)
			(end 0.8636 0.4064)
			(stroke
				(width 0.1)
				(type default)
			)
			(layer "F.Fab")
		)
		(pad "1" smd rect
			(at -0.7366 0 270)
			(size 0.7112 0.8128)
			(layers "F.Cu" "F.Mask" "F.Paste")
			(net "P52V_HS_4287_ADC_N")
		)
		(pad "2" smd rect
			(at 0.7366 0 270)
			(size 0.7112 0.8128)
			(layers "F.Cu" "F.Mask" "F.Paste")
			(net "P52V_HS1_SENSE_N_R1")
		)
	)
	(footprint ""
		(layer "F.Cu")
		(at 323.13626 -52.0954 180)
		(property "Reference" "PQ34"
			(at -9.628886 -3.917188 0)
			(unlocked yes)
			(layer "F.SilkS")
			(effects
				(font
					(size 0.7874 0.5842)
					(thickness 0.1524)
				)
				(justify left)
			)
		)
		(property "Value" ""
			(at 0 0 180)
			(layer "F.Fab")
			(effects
				(font
					(size 1.27 1.27)
				)
			)
		)
		(duplicate_pad_numbers_are_jumpers no)
		(fp_line
			(start 7.649972 4.99999)
			(end 7.649972 -4.99999)
			(stroke
				(width 0.1524)
				(type default)
			)
			(layer "F.SilkS")
		)
		(fp_line
			(start 7.649972 -4.99999)
			(end 7.630414 -4.99999)
			(stroke
				(width 0.1524)
				(type default)
			)
			(layer "F.SilkS")
		)
		(fp_line
			(start 7.630414 4.99999)
			(end 7.649972 4.99999)
			(stroke
				(width 0.1524)
				(type default)
			)
			(layer "F.SilkS")
		)
		(fp_line
			(start 5.115814 -4.99999)
			(end -7.649972 -4.99999)
			(stroke
				(width 0.1524)
				(type default)
			)
			(layer "F.SilkS")
		)
		(fp_line
			(start -7.649972 4.99999)
			(end 5.115814 4.99999)
			(stroke
				(width 0.1524)
				(type default)
			)
			(layer "F.SilkS")
		)
		(fp_line
			(start -7.649972 3.3274)
			(end -7.649972 4.99999)
			(stroke
				(width 0.1524)
				(type default)
			)
			(layer "F.SilkS")
		)
		(fp_line
			(start -7.649972 -1.7526)
			(end -7.649972 1.7526)
			(stroke
				(width 0.1524)
				(type default)
			)
			(layer "F.SilkS")
		)
		(fp_line
			(start -7.649972 -4.99999)
			(end -7.649972 -3.3274)
			(stroke
				(width 0.1524)
				(type default)
			)
			(layer "F.SilkS")
		)
		(fp_line
			(start 7.649972 4.99999)
			(end 7.649972 -4.99999)
			(stroke
				(width 0.1)
				(type default)
			)
			(layer "F.Fab")
		)
		(fp_line
			(start 7.649972 -4.99999)
			(end -7.649972 -4.99999)
			(stroke
				(width 0.1)
				(type default)
			)
			(layer "F.Fab")
		)
		(fp_line
			(start -7.649972 4.99999)
			(end 7.649972 4.99999)
			(stroke
				(width 0.1)
				(type default)
			)
			(layer "F.Fab")
		)
		(fp_line
			(start -7.649972 -4.99999)
			(end -7.649972 4.99999)
			(stroke
				(width 0.1)
				(type default)
			)
			(layer "F.Fab")
		)
		(pad "D" smd circle
			(at 2.15011 0 180)
			(size 0 0)
			(layers "F.Cu" "F.Mask" "F.Paste")
			(net "P52V_HS1_DRAIN_1")
		)
		(pad "G" smd rect
			(at -7.050024 -2.54 90)
			(size 1.3208 3.0988)
			(layers "F.Cu" "F.Mask" "F.Paste")
			(net "P52V_HS1_GATE3")
		)
		(pad "S" smd rect
			(at -7.050024 2.54 90)
			(size 1.3208 3.0988)
			(layers "F.Cu" "F.Mask" "F.Paste")
			(net "P52V_HS1")
		)
		(zone
			(layer "F.Cu")
			(hatch none 0.5)
			(connect_pads
				(clearance 0)
			)
			(min_thickness 0.25)
			(keepout
				(tracks not_allowed)
				(vias allowed)
				(pads allowed)
				(copperpour not_allowed)
				(footprints allowed)
			)
			(placement
				(enabled no)
				(sheetname "")
			)
			(fill
				(thermal_gap 0.5)
				(thermal_bridge_width 0.5)
				(island_removal_mode 0)
			)
			(polygon
				(pts
					(xy 317.95466 -47.117) (xy 330.78166 -47.117) (xy 330.78166 -48.8442) (xy 328.57186 -48.8442) (xy 328.57186 -50.2666)
					(xy 330.78166 -50.2666) (xy 330.78166 -53.9242) (xy 328.57186 -53.9242) (xy 328.57186 -55.3466)
					(xy 330.78166 -55.3466) (xy 330.78166 -57.0738) (xy 317.95466 -57.0738) (xy 317.95466 -55.9054)
					(xy 324.15226 -55.9054) (xy 324.15226 -48.2854) (xy 317.95466 -48.2854)
				)
			)
		)
	)
	(footprint ""
		(layer "F.Cu")
		(at 402.717 -17.018)
		(property "Reference" "PR101"
			(at -7.5946 1.29667 0)
			(unlocked yes)
			(layer "F.SilkS")
			(effects
				(font
					(size 0.7874 0.5842)
					(thickness 0.1524)
				)
				(justify left)
			)
		)
		(property "Value" ""
			(at 0 0 0)
			(layer "F.Fab")
			(effects
				(font
					(size 1.27 1.27)
				)
			)
		)
		(duplicate_pad_numbers_are_jumpers no)
		(fp_line
			(start -3.62712 -1.8796)
			(end -3.62712 1.8796)
			(stroke
				(width 0.1524)
				(type default)
			)
			(layer "F.SilkS")
		)
		(fp_line
			(start -3.62712 1.8796)
			(end 3.62712 1.8796)
			(stroke
				(width 0.1524)
				(type default)
			)
			(layer "F.SilkS")
		)
		(fp_line
			(start 3.62712 -1.8796)
			(end -3.62712 -1.8796)
			(stroke
				(width 0.1524)
				(type default)
			)
			(layer "F.SilkS")
		)
		(fp_line
			(start 3.62712 1.8796)
			(end 3.62712 -1.8796)
			(stroke
				(width 0.1524)
				(type default)
			)
			(layer "F.SilkS")
		)
		(fp_line
			(start -3.299968 -1.700022)
			(end -3.299968 1.700022)
			(stroke
				(width 0.1)
				(type default)
			)
			(layer "F.Fab")
		)
		(fp_line
			(start -3.299968 1.700022)
			(end 3.299968 1.700022)
			(stroke
				(width 0.1)
				(type default)
			)
			(layer "F.Fab")
		)
		(fp_line
			(start 3.299968 -1.700022)
			(end -3.299968 -1.700022)
			(stroke
				(width 0.1)
				(type default)
			)
			(layer "F.Fab")
		)
		(fp_line
			(start 3.299968 1.700022)
			(end 3.299968 -1.700022)
			(stroke
				(width 0.1)
				(type default)
			)
			(layer "F.Fab")
		)
		(pad "1" smd rect
			(at -2.70002 0)
			(size 1.6002 3.5052)
			(layers "F.Cu" "F.Mask" "F.Paste")
			(net "P52V_HS1_EN_DISCHARGE_VBE_R")
		)
		(pad "2" smd rect
			(at 2.70002 0)
			(size 1.6002 3.5052)
			(layers "F.Cu" "F.Mask" "F.Paste")
			(net "GND")
		)
	)
	(footprint ""
		(layer "F.Cu")
		(at 469.179656 -107.502452 90)
		(property "Reference" "R85"
			(at 0 0 90)
			(layer "F.SilkS")
			(hide yes)
			(effects
				(font
					(size 1.27 1.27)
				)
			)
		)
		(property "Value" ""
			(at 0 0 90)
			(layer "F.Fab")
			(effects
				(font
					(size 1.27 1.27)
				)
			)
		)
		(duplicate_pad_numbers_are_jumpers no)
		(fp_line
			(start 0.7874 -0.4064)
			(end 0.7874 0.4064)
			(stroke
				(width 0.1524)
				(type default)
			)
			(layer "F.SilkS")
		)
		(fp_line
			(start -0.7874 -0.4064)
			(end 0.7874 -0.4064)
			(stroke
				(width 0.1524)
				(type default)
			)
			(layer "F.SilkS")
		)
		(fp_line
			(start 0.7874 0.4064)
			(end -0.7874 0.4064)
			(stroke
				(width 0.1524)
				(type default)
			)
			(layer "F.SilkS")
		)
		(fp_line
			(start -0.7874 0.4064)
			(end -0.7874 -0.4064)
			(stroke
				(width 0.1524)
				(type default)
			)
			(layer "F.SilkS")
		)
		(fp_line
			(start -0.12065 -0.305054)
			(end -0.12065 -0.2794)
			(stroke
				(width 0.1)
				(type default)
			)
			(layer "F.Fab")
		)
		(fp_line
			(start -0.67945 -0.305054)
			(end -0.12065 -0.305054)
			(stroke
				(width 0.1)
				(type default)
			)
			(layer "F.Fab")
		)
		(fp_line
			(start 0.67945 -0.3048)
			(end 0.67945 0.3048)
			(stroke
				(width 0.1)
				(type default)
			)
			(layer "F.Fab")
		)
		(fp_line
			(start 0.12065 -0.3048)
			(end 0.67945 -0.3048)
			(stroke
				(width 0.1)
				(type default)
			)
			(layer "F.Fab")
		)
		(fp_line
			(start 0.12065 -0.2794)
			(end 0.12065 -0.3048)
			(stroke
				(width 0.1)
				(type default)
			)
			(layer "F.Fab")
		)
		(fp_line
			(start -0.12065 -0.2794)
			(end 0.12065 -0.2794)
			(stroke
				(width 0.1)
				(type default)
			)
			(layer "F.Fab")
		)
		(fp_line
			(start 0.120396 0.2794)
			(end -0.12065 0.2794)
			(stroke
				(width 0.1)
				(type default)
			)
			(layer "F.Fab")
		)
		(fp_line
			(start -0.12065 0.2794)
			(end -0.12065 0.3048)
			(stroke
				(width 0.1)
				(type default)
			)
			(layer "F.Fab")
		)
		(fp_line
			(start 0.67945 0.3048)
			(end 0.120396 0.3048)
			(stroke
				(width 0.1)
				(type default)
			)
			(layer "F.Fab")
		)
		(fp_line
			(start 0.120396 0.3048)
			(end 0.120396 0.2794)
			(stroke
				(width 0.1)
				(type default)
			)
			(layer "F.Fab")
		)
		(fp_line
			(start -0.12065 0.3048)
			(end -0.67945 0.3048)
			(stroke
				(width 0.1)
				(type default)
			)
			(layer "F.Fab")
		)
		(fp_line
			(start -0.67945 0.3048)
			(end -0.67945 -0.305054)
			(stroke
				(width 0.1)
				(type default)
			)
			(layer "F.Fab")
		)
		(pad "1" smd circle
			(at -0.40005 0 90)
			(size 0 0)
			(layers "F.Cu" "F.Mask" "F.Paste")
			(net "SMB_PDB_SDA")
		)
		(pad "2" smd circle
			(at 0.40005 0 90)
			(size 0 0)
			(layers "F.Cu" "F.Mask" "F.Paste")
			(net "SMB_PDB_R_SDA")
		)
	)
)
